(kicad_pcb
	(version 20241229)
	(generator "pcbnew")
	(generator_version "9.0")
	(general
		(thickness 1.294)
		(legacy_teardrops no)
	)
	(paper "A3")
	(title_block
		(title "Kintex 410T devboard")
		(date "2024-04-03")
		(rev "1.1.2")
		(comment 9 "footprints 230-234 of 975")
	)
	(layers
		(0 "F.Cu" mixed)
		(4 "In1.Cu" power)
		(6 "In2.Cu" power)
		(8 "In3.Cu" mixed)
		(10 "In4.Cu" power)
		(12 "In5.Cu" mixed)
		(14 "In6.Cu" power)
		(16 "In7.Cu" mixed)
		(18 "In8.Cu" power)
		(2 "B.Cu" mixed)
		(9 "F.Adhes" user "F.Adhesive")
		(11 "B.Adhes" user "B.Adhesive")
		(13 "F.Paste" user)
		(15 "B.Paste" user)
		(5 "F.SilkS" user "F.Silkscreen")
		(7 "B.SilkS" user "B.Silkscreen")
		(1 "F.Mask" user)
		(3 "B.Mask" user)
		(17 "Dwgs.User" user "User.Drawings")
		(19 "Cmts.User" user "User.Comments")
		(21 "Eco1.User" user "User.Eco1")
		(23 "Eco2.User" user "User.Eco2")
		(25 "Edge.Cuts" user)
		(27 "Margin" user)
		(31 "F.CrtYd" user "F.Courtyard")
		(29 "B.CrtYd" user "B.Courtyard")
		(35 "F.Fab" user)
		(33 "B.Fab" user)
	)
	(footprint "antmicro-footprints:C_0805_2012Metric"
		(layer "F.Cu")
		(at 176.05 176.1625)
		(descr "Capacitor SMD 0805")
		(tags "capacitor SMD 0805")
		(property "Reference" "C320"
			(at -1.3 3.8375 0)
			(layer "F.SilkS")
			(effects
				(font
					(size 0.7 0.7)
					(thickness 0.15)
				)
				(justify left bottom)
			)
		)
		(property "Value" "C_22u_25V_0805"
			(at 0 1.947 0)
			(layer "F.Fab")
			(effects
				(font
					(size 0.7 0.7)
					(thickness 0.15)
				)
				(justify left bottom)
			)
		)
		(property "Description" "SMT Multilayer Ceramic Capacitor, 22uF, +/-20%, 25V, X5R, 0805 [2012 Metric]"
			(at 0 0 0)
			(layer "F.Fab")
			(hide yes)
			(effects
				(font
					(size 1.27 1.27)
					(thickness 0.15)
				)
			)
		)
		(property "Author" "Antmicro"
			(at 0 0 0)
			(layer "F.Fab")
			(hide yes)
			(effects
				(font
					(size 1 1)
					(thickness 0.15)
				)
			)
		)
		(property "Dielectric" "X5R"
			(at 0 0 0)
			(layer "F.Fab")
			(hide yes)
			(effects
				(font
					(size 1 1)
					(thickness 0.15)
				)
			)
		)
		(property "License" "Apache-2.0"
			(at 0 0 0)
			(layer "F.Fab")
			(hide yes)
			(effects
				(font
					(size 1 1)
					(thickness 0.15)
				)
			)
		)
		(property "MPN" "CL21A226MAYNNNE"
			(at 0 0 0)
			(layer "F.Fab")
			(hide yes)
			(effects
				(font
					(size 1 1)
					(thickness 0.15)
				)
			)
		)
		(property "Manufacturer" "Samsung Electro-Mechanics"
			(at 0 0 0)
			(layer "F.Fab")
			(hide yes)
			(effects
				(font
					(size 1 1)
					(thickness 0.15)
				)
			)
		)
		(property "Val" "22u"
			(at 0 0 0)
			(layer "F.Fab")
			(hide yes)
			(effects
				(font
					(size 1 1)
					(thickness 0.15)
				)
			)
		)
		(property "Voltage" "25V"
			(at 0 0 0)
			(layer "F.Fab")
			(hide yes)
			(effects
				(font
					(size 1 1)
					(thickness 0.15)
				)
			)
		)
		(sheetname "DC-DC Converters")
		(sheetfile "dc-dc.kicad_sch")
		(attr smd)
		(fp_line
			(start -0.3 -0.7)
			(end 0.3 -0.7)
			(stroke
				(width 0.15)
				(type solid)
			)
			(layer "F.SilkS")
		)
		(fp_line
			(start -0.3 0.7)
			(end 0.3 0.7)
			(stroke
				(width 0.15)
				(type solid)
			)
			(layer "F.SilkS")
		)
		(fp_rect
			(start 1.95 -0.9)
			(end -1.95 0.9)
			(stroke
				(width 0.05)
				(type default)
			)
			(fill no)
			(layer "F.CrtYd")
		)
		(fp_rect
			(start -0.95 -0.675)
			(end 0.95 0.675)
			(stroke
				(width 0.15)
				(type solid)
			)
			(fill no)
			(layer "F.Fab")
		)
		(pad "1" smd roundrect
			(at -1.1 0)
			(size 1.2 1.3)
			(layers "F.Cu" "F.Mask" "F.Paste")
			(roundrect_rratio 0.25)
			(net 1 "GND")
			(pintype "passive")
		)
		(pad "2" smd roundrect
			(at 1.1 0)
			(size 1.2 1.3)
			(layers "F.Cu" "F.Mask" "F.Paste")
			(roundrect_rratio 0.25)
			(net 702 "VDC")
			(pintype "passive")
		)
	)
	(footprint "antmicro-footprints:D_SOD-123F"
		(layer "F.Cu")
		(at 249.6 179.7)
		(property "Reference" "D10"
			(at 2.15 0.35 0)
			(layer "F.SilkS")
			(effects
				(font
					(size 0.7 0.7)
					(thickness 0.15)
				)
				(justify left bottom)
			)
		)
		(property "Value" "PTVS58VS1UR,115"
			(at 0 2.1 0)
			(layer "F.Fab")
			(effects
				(font
					(size 0.7 0.7)
					(thickness 0.15)
				)
				(justify left bottom)
			)
		)
		(property "Description" "Unidirectional TVS, 8 kV,  SOD-123F, 58 V"
			(at 0 0 0)
			(layer "F.Fab")
			(hide yes)
			(effects
				(font
					(size 1.27 1.27)
					(thickness 0.15)
				)
			)
		)
		(property "Author" "Antmicro"
			(at 0 0 0)
			(layer "F.Fab")
			(hide yes)
			(effects
				(font
					(size 1 1)
					(thickness 0.15)
				)
			)
		)
		(property "License" "Apache-2.0"
			(at 0 0 0)
			(layer "F.Fab")
			(hide yes)
			(effects
				(font
					(size 1 1)
					(thickness 0.15)
				)
			)
		)
		(property "MPN" "PTVS58VS1UR,115"
			(at 0 0 0)
			(layer "F.Fab")
			(hide yes)
			(effects
				(font
					(size 1 1)
					(thickness 0.15)
				)
			)
		)
		(property "Manufacturer" "Nexperia"
			(at 0 0 0)
			(layer "F.Fab")
			(hide yes)
			(effects
				(font
					(size 1 1)
					(thickness 0.15)
				)
			)
		)
		(property "Public" "False"
			(at 0 0 0)
			(layer "F.Fab")
			(hide yes)
			(effects
				(font
					(size 1 1)
					(thickness 0.15)
				)
			)
		)
		(sheetname "Power supply")
		(sheetfile "power-supply.kicad_sch")
		(attr smd)
		(fp_line
			(start -0.65 -0.6)
			(end -0.65 0.6)
			(stroke
				(width 0.15)
				(type solid)
			)
			(layer "F.SilkS")
		)
		(fp_line
			(start -2.21 1.1)
			(end -2.21 -1.1)
			(stroke
				(width 0.05)
				(type solid)
			)
			(layer "F.CrtYd")
		)
		(fp_line
			(start 2.2 -1.1)
			(end -2.21 -1.1)
			(stroke
				(width 0.05)
				(type solid)
			)
			(layer "F.CrtYd")
		)
		(fp_line
			(start 2.2 -1.1)
			(end 2.2 1.1)
			(stroke
				(width 0.05)
				(type solid)
			)
			(layer "F.CrtYd")
		)
		(fp_line
			(start 2.2 1.1)
			(end -2.21 1.1)
			(stroke
				(width 0.05)
				(type solid)
			)
			(layer "F.CrtYd")
		)
		(fp_line
			(start -0.8 -0.8)
			(end -0.8 0.8)
			(stroke
				(width 0.1)
				(type solid)
			)
			(layer "F.Fab")
		)
		(fp_rect
			(start -1.75 -0.802)
			(end 1.749 0.8)
			(stroke
				(width 0.1)
				(type solid)
			)
			(fill no)
			(layer "F.Fab")
		)
		(pad "1" smd roundrect
			(at -1.401 0)
			(size 1.2 1.2)
			(layers "F.Cu" "F.Mask" "F.Paste")
			(roundrect_rratio 0.25)
			(net 698 "/Power supply/VDD")
			(pinfunction "C")
			(pintype "passive")
		)
		(pad "2" smd roundrect
			(at 1.398 0)
			(size 1.2 1.2)
			(layers "F.Cu" "F.Mask" "F.Paste")
			(roundrect_rratio 0.25)
			(net 697 "/Power supply/VSS")
			(pinfunction "A")
			(pintype "passive")
		)
	)
	(footprint "antmicro-footprints:Conn_JST_SH_1x4_BM04B-SRSS-TB-LF-SN"
		(layer "F.Cu")
		(at 230.8 127.4 -90)
		(property "Reference" "J8"
			(at -1.9 1.95 90)
			(layer "F.SilkS")
			(effects
				(font
					(size 0.7 0.7)
					(thickness 0.15)
				)
				(justify right bottom)
			)
		)
		(property "Value" "JST_SH_1x4_BM04B-SRSS-TB-LF-SN"
			(at 0 3.1 90)
			(layer "F.Fab")
			(effects
				(font
					(size 0.7 0.7)
					(thickness 0.15)
				)
				(justify right bottom)
			)
		)
		(property "Description" "Pin Header, Top Entry, Wire-to-Board, 1 mm, 1 Rows, 4 Contacts, Surface Mount, SR"
			(at 0 0 270)
			(layer "F.Fab")
			(hide yes)
			(effects
				(font
					(size 1.27 1.27)
					(thickness 0.15)
				)
			)
		)
		(property "Author" "Antmicro"
			(at 103.4 358.2 0)
			(layer "F.Fab")
			(hide yes)
			(effects
				(font
					(size 1 1)
					(thickness 0.15)
				)
			)
		)
		(property "License" "Apache-2.0"
			(at 103.4 358.2 0)
			(layer "F.Fab")
			(hide yes)
			(effects
				(font
					(size 1 1)
					(thickness 0.15)
				)
			)
		)
		(property "MPN" "BM04B-SRSS-TB(LF)(SN) "
			(at 103.4 358.2 0)
			(layer "F.Fab")
			(hide yes)
			(effects
				(font
					(size 1 1)
					(thickness 0.15)
				)
			)
		)
		(property "Manufacturer" "JST Automotive Connectors"
			(at 103.4 358.2 0)
			(layer "F.Fab")
			(hide yes)
			(effects
				(font
					(size 1 1)
					(thickness 0.15)
				)
			)
		)
		(sheetname "User GPIO + LED + button + DIP switch")
		(sheetfile "user-gpio.kicad_sch")
		(attr smd)
		(fp_line
			(start -1.125 2.999)
			(end -1.125 2.201)
			(stroke
				(width 0.15)
				(type solid)
			)
			(layer "F.SilkS")
		)
		(fp_line
			(start -0.251 2.999)
			(end -1.125 2.999)
			(stroke
				(width 0.15)
				(type solid)
			)
			(layer "F.SilkS")
		)
		(fp_line
			(start 1.774 -1.7)
			(end 1.774 1.702)
			(stroke
				(width 0.15)
				(type solid)
			)
			(layer "F.SilkS")
		)
		(fp_line
			(start -1.125 -2.999)
			(end -1.125 -2.201)
			(stroke
				(width 0.15)
				(type solid)
			)
			(layer "F.SilkS")
		)
		(fp_line
			(start -0.251 -2.999)
			(end -1.125 -2.999)
			(stroke
				(width 0.15)
				(type solid)
			)
			(layer "F.SilkS")
		)
		(fp_circle
			(center -1.6 -2.1)
			(end -1.55 -2.1)
			(stroke
				(width 0.15)
				(type solid)
			)
			(fill yes)
			(layer "F.SilkS")
		)
		(fp_rect
			(start -2.05 -3.95)
			(end 2.05 3.95)
			(stroke
				(width 0.05)
				(type solid)
			)
			(fill no)
			(layer "F.CrtYd")
		)
		(fp_rect
			(start -1.8 -3)
			(end 1.8 3)
			(stroke
				(width 0.15)
				(type solid)
			)
			(fill no)
			(layer "F.Fab")
		)
		(pad "1" smd roundrect
			(at -1.45 -1.5 180)
			(size 0.6 1.55)
			(layers "F.Cu" "F.Mask" "F.Paste")
			(roundrect_rratio 0.25)
			(net 1 "GND")
			(pinfunction "Pin_1")
			(pintype "passive")
		)
		(pad "2" smd roundrect
			(at -1.45 -0.5 180)
			(size 0.6 1.55)
			(layers "F.Cu" "F.Mask" "F.Paste")
			(roundrect_rratio 0.25)
			(net 703 "+5V")
			(pinfunction "Pin_2")
			(pintype "passive")
		)
		(pad "3" smd roundrect
			(at -1.45 0.5 180)
			(size 0.6 1.55)
			(layers "F.Cu" "F.Mask" "F.Paste")
			(roundrect_rratio 0.25)
			(net 31 "unconnected-(J8-Pin_3-Pad3)")
			(pinfunction "Pin_3")
			(pintype "passive+no_connect")
		)
		(pad "4" smd roundrect
			(at -1.45 1.5 180)
			(size 0.6 1.55)
			(layers "F.Cu" "F.Mask" "F.Paste")
			(roundrect_rratio 0.25)
			(net 801 "/User GPIO + LED + button + DIP switch/FAN_PWM_PIN")
			(pinfunction "Pin_4")
			(pintype "passive")
		)
		(pad "MP" smd roundrect
			(at 1.075 -2.8 180)
			(size 1.2 1.8)
			(layers "F.Cu" "F.Mask" "F.Paste")
			(roundrect_rratio 0.25)
			(net 1 "GND")
			(pinfunction "MP")
			(pintype "passive")
		)
		(pad "MP" smd roundrect
			(at 1.075 2.8 180)
			(size 1.2 1.8)
			(layers "F.Cu" "F.Mask" "F.Paste")
			(roundrect_rratio 0.25)
			(net 1 "GND")
			(pinfunction "MP")
			(pintype "passive")
		)
	)
	(footprint "antmicro-footprints:LED_0603_1608Metric_R"
		(layer "F.Cu")
		(at 261.5 79)
		(descr "LED SMD 0603 Red")
		(tags "LED SMD 0603 Red")
		(property "Reference" "D24"
			(at -1.15 1.5 0)
			(layer "F.SilkS")
			(effects
				(font
					(size 0.7 0.7)
					(thickness 0.15)
				)
				(justify left bottom)
			)
		)
		(property "Value" "LED_R_0603_KP-1608EC"
			(at 0 1.6 0)
			(layer "F.Fab")
			(effects
				(font
					(size 0.7 0.7)
					(thickness 0.15)
				)
				(justify left bottom)
			)
		)
		(property "Description" "LED, Red, SMD, 0603, 30 mA, 2 V, 617 nm"
			(at 0 0 0)
			(layer "F.Fab")
			(hide yes)
			(effects
				(font
					(size 1.27 1.27)
					(thickness 0.15)
				)
			)
		)
		(property "Author" "Antmicro"
			(at 0 0 0)
			(layer "F.Fab")
			(hide yes)
			(effects
				(font
					(size 1 1)
					(thickness 0.15)
				)
			)
		)
		(property "Color" "Red"
			(at 0 0 0)
			(layer "F.Fab")
			(hide yes)
			(effects
				(font
					(size 1 1)
					(thickness 0.15)
				)
			)
		)
		(property "License" "Apache-2.0"
			(at 0 0 0)
			(layer "F.Fab")
			(hide yes)
			(effects
				(font
					(size 1 1)
					(thickness 0.15)
				)
			)
		)
		(property "MPN" "KP-1608EC"
			(at 0 0 0)
			(layer "F.Fab")
			(hide yes)
			(effects
				(font
					(size 1 1)
					(thickness 0.15)
				)
			)
		)
		(property "Manufacturer" "Kingbright"
			(at 0 0 0)
			(layer "F.Fab")
			(hide yes)
			(effects
				(font
					(size 1 1)
					(thickness 0.15)
				)
			)
		)
		(property "Public" "False"
			(at 0 0 0)
			(layer "F.Fab")
			(hide yes)
			(effects
				(font
					(size 1 1)
					(thickness 0.15)
				)
			)
		)
		(sheetname "User GPIO + LED + button + DIP switch")
		(sheetfile "user-gpio.kicad_sch")
		(attr smd)
		(fp_line
			(start -1.18 -0.319)
			(end -1.18 0.321)
			(stroke
				(width 0.15)
				(type solid)
			)
			(layer "F.SilkS")
		)
		(fp_line
			(start -0.094672 0.001008)
			(end -0.24 0.001008)
			(stroke
				(width 0.1)
				(type solid)
			)
			(layer "F.SilkS")
		)
		(fp_line
			(start -0.094672 0.001008)
			(end 0.105328 -0.198992)
			(stroke
				(width 0.1)
				(type solid)
			)
			(layer "F.SilkS")
		)
		(fp_line
			(start -0.094672 0.201008)
			(end -0.094672 -0.198992)
			(stroke
				(width 0.1)
				(type solid)
			)
			(layer "F.SilkS")
		)
		(fp_line
			(start 0.105328 0.001008)
			(end 0.24 0.001)
			(stroke
				(width 0.1)
				(type solid)
			)
			(layer "F.SilkS")
		)
		(fp_line
			(start 0.105328 0.201008)
			(end -0.094672 0.001008)
			(stroke
				(width 0.1)
				(type solid)
			)
			(layer "F.SilkS")
		)
		(fp_line
			(start 0.105328 0.201008)
			(end 0.105328 -0.198992)
			(stroke
				(width 0.1)
				(type solid)
			)
			(layer "F.SilkS")
		)
		(fp_line
			(start 0.22 -0.35)
			(end -0.22 -0.35)
			(stroke
				(width 0.15)
				(type solid)
			)
			(layer "F.SilkS")
		)
		(fp_line
			(start 0.22 0.35)
			(end -0.22 0.35)
			(stroke
				(width 0.15)
				(type solid)
			)
			(layer "F.SilkS")
		)
		(fp_rect
			(start 1.25 0.65)
			(end -1.25 -0.65)
			(stroke
				(width 0.05)
				(type solid)
			)
			(fill no)
			(layer "F.CrtYd")
		)
		(fp_line
			(start -0.199 -0.202)
			(end -0.199 0.1)
			(stroke
				(width 0.15)
				(type solid)
			)
			(layer "F.Fab")
		)
		(fp_line
			(start -0.199 0)
			(end -0.597 0)
			(stroke
				(width 0.15)
				(type solid)
			)
			(layer "F.Fab")
		)
		(fp_line
			(start -0.199 0.2)
			(end -0.199 0.1)
			(stroke
				(width 0.15)
				(type solid)
			)
			(layer "F.Fab")
		)
		(fp_line
			(start -0.101 0)
			(end 0.201 0.2)
			(stroke
				(width 0.15)
				(type solid)
			)
			(layer "F.Fab")
		)
		(fp_line
			(start 0.201 -0.202)
			(end -0.101 0)
			(stroke
				(width 0.15)
				(type solid)
			)
			(layer "F.Fab")
		)
		(fp_line
			(start 0.201 0)
			(end 0.201 -0.202)
			(stroke
				(width 0.15)
				(type solid)
			)
			(layer "F.Fab")
		)
		(fp_line
			(start 0.201 0.2)
			(end 0.201 0)
			(stroke
				(width 0.15)
				(type solid)
			)
			(layer "F.Fab")
		)
		(fp_line
			(start 0.599 0)
			(end 0.201 0)
			(stroke
				(width 0.15)
				(type solid)
			)
			(layer "F.Fab")
		)
		(fp_rect
			(start 0.848 0.4)
			(end -0.85 -0.402)
			(stroke
				(width 0.15)
				(type solid)
			)
			(fill no)
			(layer "F.Fab")
		)
		(pad "1" smd roundrect
			(at -0.7 0 180)
			(size 0.8 1)
			(layers "F.Cu" "F.Mask" "F.Paste")
			(roundrect_rratio 0.2)
			(net 770 "Net-(D24-C)")
			(pinfunction "C")
			(pintype "passive")
		)
		(pad "2" smd roundrect
			(at 0.7 0 180)
			(size 0.8 1)
			(layers "F.Cu" "F.Mask" "F.Paste")
			(roundrect_rratio 0.2)
			(net 773 "Net-(D24-A)")
			(pinfunction "A")
			(pintype "passive")
		)
	)
	(footprint "antmicro-footprints:R_0603_1608Metric"
		(layer "F.Cu")
		(at 197.8 153.624 90)
		(descr "Resistor SMD 0603")
		(tags "resistor SMD 0603")
		(property "Reference" "R37"
			(at 1.174 -1.1 180)
			(layer "F.SilkS")
			(effects
				(font
					(size 0.7 0.7)
					(thickness 0.15)
				)
				(justify left bottom)
			)
		)
		(property "Value" "R_0R_22.4A_0603"
			(at 0 1.6 90)
			(layer "F.Fab")
			(effects
				(font
					(size 0.7 0.7)
					(thickness 0.15)
				)
				(justify left bottom)
			)
		)
		(property "Description" "SMD Chip Resistor"
			(at 0 0 90)
			(layer "F.Fab")
			(hide yes)
			(effects
				(font
					(size 1.27 1.27)
					(thickness 0.15)
				)
			)
		)
		(property "Author" "Antmicro"
			(at 351.424 -44.176 0)
			(layer "F.Fab")
			(hide yes)
			(effects
				(font
					(size 1 1)
					(thickness 0.15)
				)
			)
		)
		(property "License" "Apache-2.0"
			(at 351.424 -44.176 0)
			(layer "F.Fab")
			(hide yes)
			(effects
				(font
					(size 1 1)
					(thickness 0.15)
				)
			)
		)
		(property "MPN" "PMR03EZPJ000"
			(at 351.424 -44.176 0)
			(layer "F.Fab")
			(hide yes)
			(effects
				(font
					(size 1 1)
					(thickness 0.15)
				)
			)
		)
		(property "Manufacturer" "ROHM Semiconductor"
			(at 351.424 -44.176 0)
			(layer "F.Fab")
			(hide yes)
			(effects
				(font
					(size 1 1)
					(thickness 0.15)
				)
			)
		)
		(property "Max. Curr." "22.4A"
			(at 351.424 -44.176 0)
			(layer "F.Fab")
			(hide yes)
			(effects
				(font
					(size 1 1)
					(thickness 0.15)
				)
			)
		)
		(property "Tolerance" "template_tolerance"
			(at 351.424 -44.176 0)
			(layer "F.Fab")
			(hide yes)
			(effects
				(font
					(size 1 1)
					(thickness 0.15)
				)
			)
		)
		(property "Val" "0R"
			(at 351.424 -44.176 0)
			(layer "F.Fab")
			(hide yes)
			(effects
				(font
					(size 1 1)
					(thickness 0.15)
				)
			)
		)
		(sheetname "DC-DC Converters")
		(sheetfile "dc-dc.kicad_sch")
		(attr smd)
		(fp_line
			(start -0.15 -0.4)
			(end 0.15 -0.4)
			(stroke
				(width 0.15)
				(type solid)
			)
			(layer "F.SilkS")
		)
		(fp_line
			(start -0.15 0.4)
			(end 0.15 0.4)
			(stroke
				(width 0.15)
				(type solid)
			)
			(layer "F.SilkS")
		)
		(fp_rect
			(start -1.25 -0.65)
			(end 1.25 0.65)
			(stroke
				(width 0.05)
				(type solid)
			)
			(fill no)
			(layer "F.CrtYd")
		)
		(fp_rect
			(start -0.8 -0.4)
			(end 0.8 0.4)
			(stroke
				(width 0.15)
				(type solid)
			)
			(fill no)
			(layer "F.Fab")
		)
		(pad "1" smd roundrect
			(at -0.7 0 90)
			(size 0.8 1)
			(layers "F.Cu" "F.Mask" "F.Paste")
			(roundrect_rratio 0.2)
			(net 751 "/DC-DC Converters/1V0_REG")
			(pintype "passive")
		)
		(pad "2" smd roundrect
			(at 0.7 0 90)
			(size 0.8 1)
			(layers "F.Cu" "F.Mask" "F.Paste")
			(roundrect_rratio 0.2)
			(net 650 "+1V0")
			(pintype "passive")
		)
	)
)
